(kicad_pcb
	(version 20260206)
	(generator "pcbnew")
	(generator_version "10.0")
	(general
		(thickness 1.6)
		(legacy_teardrops no)
	)
	(paper "A4")
	(title_block
		(title "04192023_DAF0TMB3IC0_F0TG_MB_C_brd_V02_OCP.brd")
		(comment 1 "Grand Teton / footprints 7754-7760 of 8354")
	)
	(layers
		(0 "F.Cu" signal "TOP")
		(4 "In1.Cu" signal "GND")
		(6 "In2.Cu" signal "IN1")
		(8 "In3.Cu" signal "GND1")
		(10 "In4.Cu" signal "IN2")
		(12 "In5.Cu" signal "GND2")
		(14 "In6.Cu" signal "IN3")
		(16 "In7.Cu" signal "GND3")
		(18 "In8.Cu" signal "VCC")
		(20 "In9.Cu" signal "VCC1")
		(22 "In10.Cu" signal "GND4")
		(24 "In11.Cu" signal "IN4")
		(26 "In12.Cu" signal "GND5")
		(28 "In13.Cu" signal "IN5")
		(30 "In14.Cu" signal "GND6")
		(32 "In15.Cu" signal "IN6")
		(34 "In16.Cu" signal "GND7")
		(2 "B.Cu" signal "BOTTOM")
		(9 "F.Adhes" user "F.Adhesive")
		(11 "B.Adhes" user "B.Adhesive")
		(13 "F.Paste" user "Package Geometry/Pastemask Top")
		(15 "B.Paste" user "Package Geometry/Pastemask Bottom")
		(5 "F.SilkS" user "Ref Des/Silkscreen Top")
		(7 "B.SilkS" user "Ref Des/Silkscreen Bottom")
		(1 "F.Mask" user "Board Geometry/Soldermask Top")
		(3 "B.Mask" user "Board Geometry/Soldermask Bottom")
		(17 "Dwgs.User" user "User.Drawings")
		(19 "Cmts.User" user "User.Comments")
		(21 "Eco1.User" user "User.Eco1")
		(23 "Eco2.User" user "User.Eco2")
		(25 "Edge.Cuts" user "Board Geometry/Outline")
		(27 "Margin" user)
		(31 "F.CrtYd" user "Package Geometry/Place Bound Top")
		(29 "B.CrtYd" user "Package Geometry/Place Bound Bottom")
		(35 "F.Fab" user "Ref Des/Assembly Top")
		(33 "B.Fab" user "Ref Des/Assembly Bottom")
	)
	(footprint ""
		(layer "B.Cu")
		(at 68.143374 -177.349912 90)
		(property "Reference" "PC315_5"
			(at 0 0 90)
			(layer "B.SilkS")
			(hide yes)
			(effects
				(font
					(size 1.27 1.27)
				)
				(justify mirror)
			)
		)
		(property "Value" ""
			(at 0 0 90)
			(layer "B.Fab")
			(effects
				(font
					(size 1.27 1.27)
				)
				(justify mirror)
			)
		)
		(duplicate_pad_numbers_are_jumpers no)
		(fp_line
			(start 1.524 -0.762)
			(end -1.524 -0.762)
			(stroke
				(width 0.1524)
				(type default)
			)
			(layer "B.SilkS")
		)
		(fp_line
			(start -1.524 -0.762)
			(end -1.524 0.762)
			(stroke
				(width 0.1524)
				(type default)
			)
			(layer "B.SilkS")
		)
		(fp_line
			(start 1.524 0.762)
			(end 1.524 -0.762)
			(stroke
				(width 0.1524)
				(type default)
			)
			(layer "B.SilkS")
		)
		(fp_line
			(start -1.524 0.762)
			(end 1.524 0.762)
			(stroke
				(width 0.1524)
				(type default)
			)
			(layer "B.SilkS")
		)
		(fp_line
			(start 1.1049 -0.724916)
			(end 1.1049 0.724916)
			(stroke
				(width 0.1)
				(type default)
			)
			(layer "B.Fab")
		)
		(fp_line
			(start -1.1049 -0.724916)
			(end 1.1049 -0.724916)
			(stroke
				(width 0.1)
				(type default)
			)
			(layer "B.Fab")
		)
		(fp_line
			(start 1.1049 0.724916)
			(end -1.1049 0.724916)
			(stroke
				(width 0.1)
				(type default)
			)
			(layer "B.Fab")
		)
		(fp_line
			(start -1.1049 0.724916)
			(end -1.1049 -0.724916)
			(stroke
				(width 0.1)
				(type default)
			)
			(layer "B.Fab")
		)
		(pad "1" smd rect
			(at 0.889 0 90)
			(size 1.016 1.27)
			(layers "B.Cu" "B.Mask" "B.Paste")
			(net "PVDDCR_CPU0_P1")
		)
		(pad "2" smd rect
			(at -0.889 0 90)
			(size 1.016 1.27)
			(layers "B.Cu" "B.Mask" "B.Paste")
			(net "GND")
		)
	)
	(footprint ""
		(layer "B.Cu")
		(at 402.11502 -399.722848 -90)
		(property "Reference" "C970"
			(at 0 0 90)
			(layer "B.SilkS")
			(hide yes)
			(effects
				(font
					(size 1.27 1.27)
				)
				(justify mirror)
			)
		)
		(property "Value" ""
			(at 0 0 90)
			(layer "B.Fab")
			(effects
				(font
					(size 1.27 1.27)
				)
				(justify mirror)
			)
		)
		(duplicate_pad_numbers_are_jumpers no)
		(fp_line
			(start -0.7874 0.4064)
			(end 0.7874 0.4064)
			(stroke
				(width 0.1524)
				(type default)
			)
			(layer "B.SilkS")
		)
		(fp_line
			(start 0.7874 0.4064)
			(end 0.7874 -0.4064)
			(stroke
				(width 0.1524)
				(type default)
			)
			(layer "B.SilkS")
		)
		(fp_line
			(start -0.7874 -0.4064)
			(end -0.7874 0.4064)
			(stroke
				(width 0.1524)
				(type default)
			)
			(layer "B.SilkS")
		)
		(fp_line
			(start 0.7874 -0.4064)
			(end -0.7874 -0.4064)
			(stroke
				(width 0.1524)
				(type default)
			)
			(layer "B.SilkS")
		)
		(fp_line
			(start -0.67945 0.3048)
			(end -0.120396 0.3048)
			(stroke
				(width 0.1)
				(type default)
			)
			(layer "B.Fab")
		)
		(fp_line
			(start -0.120396 0.3048)
			(end -0.120396 0.2794)
			(stroke
				(width 0.1)
				(type default)
			)
			(layer "B.Fab")
		)
		(fp_line
			(start 0.12065 0.3048)
			(end 0.67945 0.3048)
			(stroke
				(width 0.1)
				(type default)
			)
			(layer "B.Fab")
		)
		(fp_line
			(start 0.67945 0.3048)
			(end 0.67945 -0.305054)
			(stroke
				(width 0.1)
				(type default)
			)
			(layer "B.Fab")
		)
		(fp_line
			(start -0.120396 0.2794)
			(end 0.12065 0.2794)
			(stroke
				(width 0.1)
				(type default)
			)
			(layer "B.Fab")
		)
		(fp_line
			(start 0.12065 0.2794)
			(end 0.12065 0.3048)
			(stroke
				(width 0.1)
				(type default)
			)
			(layer "B.Fab")
		)
		(fp_line
			(start -0.12065 -0.2794)
			(end -0.12065 -0.3048)
			(stroke
				(width 0.1)
				(type default)
			)
			(layer "B.Fab")
		)
		(fp_line
			(start 0.12065 -0.2794)
			(end -0.12065 -0.2794)
			(stroke
				(width 0.1)
				(type default)
			)
			(layer "B.Fab")
		)
		(fp_line
			(start -0.67945 -0.3048)
			(end -0.67945 0.3048)
			(stroke
				(width 0.1)
				(type default)
			)
			(layer "B.Fab")
		)
		(fp_line
			(start -0.12065 -0.3048)
			(end -0.67945 -0.3048)
			(stroke
				(width 0.1)
				(type default)
			)
			(layer "B.Fab")
		)
		(fp_line
			(start 0.12065 -0.305054)
			(end 0.12065 -0.2794)
			(stroke
				(width 0.1)
				(type default)
			)
			(layer "B.Fab")
		)
		(fp_line
			(start 0.67945 -0.305054)
			(end 0.12065 -0.305054)
			(stroke
				(width 0.1)
				(type default)
			)
			(layer "B.Fab")
		)
		(pad "1" smd circle
			(at 0.40005 0 90)
			(size 0 0)
			(layers "B.Cu" "B.Mask" "B.Paste")
			(net "P0V9_CPU0_RT2_2A")
		)
		(pad "2" smd circle
			(at -0.40005 0 90)
			(size 0 0)
			(layers "B.Cu" "B.Mask" "B.Paste")
			(net "GND")
		)
	)
	(footprint ""
		(layer "B.Cu")
		(at 346.464636 -157.37586 90)
		(property "Reference" "PC157_6"
			(at 0 0 90)
			(layer "B.SilkS")
			(hide yes)
			(effects
				(font
					(size 1.27 1.27)
				)
				(justify mirror)
			)
		)
		(property "Value" ""
			(at 0 0 90)
			(layer "B.Fab")
			(effects
				(font
					(size 1.27 1.27)
				)
				(justify mirror)
			)
		)
		(duplicate_pad_numbers_are_jumpers no)
		(fp_line
			(start 1.524 -0.762)
			(end -1.524 -0.762)
			(stroke
				(width 0.1524)
				(type default)
			)
			(layer "B.SilkS")
		)
		(fp_line
			(start -1.524 -0.762)
			(end -1.524 0.762)
			(stroke
				(width 0.1524)
				(type default)
			)
			(layer "B.SilkS")
		)
		(fp_line
			(start 1.524 0.762)
			(end 1.524 -0.762)
			(stroke
				(width 0.1524)
				(type default)
			)
			(layer "B.SilkS")
		)
		(fp_line
			(start -1.524 0.762)
			(end 1.524 0.762)
			(stroke
				(width 0.1524)
				(type default)
			)
			(layer "B.SilkS")
		)
		(fp_line
			(start 1.1049 -0.724916)
			(end 1.1049 0.724916)
			(stroke
				(width 0.1)
				(type default)
			)
			(layer "B.Fab")
		)
		(fp_line
			(start -1.1049 -0.724916)
			(end 1.1049 -0.724916)
			(stroke
				(width 0.1)
				(type default)
			)
			(layer "B.Fab")
		)
		(fp_line
			(start 1.1049 0.724916)
			(end -1.1049 0.724916)
			(stroke
				(width 0.1)
				(type default)
			)
			(layer "B.Fab")
		)
		(fp_line
			(start -1.1049 0.724916)
			(end -1.1049 -0.724916)
			(stroke
				(width 0.1)
				(type default)
			)
			(layer "B.Fab")
		)
		(pad "1" smd rect
			(at 0.889 0 90)
			(size 1.016 1.27)
			(layers "B.Cu" "B.Mask" "B.Paste")
			(net "SW_P12V_AUX_PVDDCR_CPU0_P0_FLT")
		)
		(pad "2" smd rect
			(at -0.889 0 90)
			(size 1.016 1.27)
			(layers "B.Cu" "B.Mask" "B.Paste")
			(net "GND")
		)
	)
	(footprint ""
		(layer "B.Cu")
		(at 506.598428 -142.846806 -90)
		(property "Reference" "X8027"
			(at 4.4577 -1.50495 270)
			(unlocked yes)
			(layer "B.SilkS")
			(effects
				(font
					(size 0.7874 0.5842)
					(thickness 0.1524)
				)
				(justify left mirror)
			)
		)
		(property "Value" ""
			(at 0 0 90)
			(layer "B.Fab")
			(effects
				(font
					(size 1.27 1.27)
				)
				(justify mirror)
			)
		)
		(property "Device Type" "TP_TDR_4P_FTS_TH-TP_TDR_4P_DIP,EMPTY,TP15"
			(at -1.30175 1.27 180)
			(unlocked yes)
			(layer "B.Fab")
			(hide yes)
			(effects
				(font
					(size 0.635 0.4064)
					(thickness 0.1524)
				)
				(justify mirror)
			)
		)
		(property "User Part Number" "N_A"
			(at -1.30175 1.27 180)
			(unlocked yes)
			(layer "Cmts.User")
			(hide yes)
			(effects
				(font
					(size 0.635 0.4064)
					(thickness 0.1524)
				)
				(justify mirror)
			)
		)
		(duplicate_pad_numbers_are_jumpers no)
		(fp_line
			(start -2.54 3.81)
			(end -2.54 3.6703)
			(stroke
				(width 0.1524)
				(type default)
			)
			(layer "B.SilkS")
		)
		(fp_line
			(start 0 3.81)
			(end -2.54 3.81)
			(stroke
				(width 0.1524)
				(type default)
			)
			(layer "B.SilkS")
		)
		(fp_line
			(start 0 3.175)
			(end 0 3.81)
			(stroke
				(width 0.1524)
				(type default)
			)
			(layer "B.SilkS")
		)
		(fp_line
			(start -2.54 1.4097)
			(end -2.54 1.1303)
			(stroke
				(width 0.1524)
				(type default)
			)
			(layer "B.SilkS")
		)
		(fp_line
			(start 0 0.635)
			(end 0 1.905)
			(stroke
				(width 0.1524)
				(type default)
			)
			(layer "B.SilkS")
		)
		(fp_line
			(start -2.54 -1.1303)
			(end -2.54 -1.27)
			(stroke
				(width 0.1524)
				(type default)
			)
			(layer "B.SilkS")
		)
		(fp_line
			(start -2.54 -1.27)
			(end 0 -1.27)
			(stroke
				(width 0.1524)
				(type default)
			)
			(layer "B.SilkS")
		)
		(fp_line
			(start 0 -1.27)
			(end 0 -0.635)
			(stroke
				(width 0.1524)
				(type default)
			)
			(layer "B.SilkS")
		)
		(fp_poly
			(pts
				(xy 0.761746 0) (xy 2.285746 -0.762) (xy 2.285746 0.762)
			)
			(stroke
				(width 0)
				(type default)
			)
			(fill yes)
			(layer "B.SilkS")
		)
		(fp_line
			(start -2.54 3.81)
			(end -2.54 -1.27)
			(stroke
				(width 0.1)
				(type default)
			)
			(layer "B.Fab")
		)
		(fp_line
			(start 0 3.81)
			(end -2.54 3.81)
			(stroke
				(width 0.1)
				(type default)
			)
			(layer "B.Fab")
		)
		(fp_line
			(start -2.54 -1.27)
			(end 0 -1.27)
			(stroke
				(width 0.1)
				(type default)
			)
			(layer "B.Fab")
		)
		(fp_line
			(start 0 -1.27)
			(end 0 3.81)
			(stroke
				(width 0.1)
				(type default)
			)
			(layer "B.Fab")
		)
		(fp_poly
			(pts
				(xy 0.761746 0) (xy 2.285746 -0.762) (xy 2.285746 0.762)
			)
			(stroke
				(width 0)
				(type default)
			)
			(fill yes)
			(layer "B.Fab")
		)
		(pad "1" thru_hole circle
			(at 0 0 90)
			(size 1.0033 1.0033)
			(drill 0.249936)
			(layers "*.Cu" "*.Mask")
			(remove_unused_layers no)
			(net "TDR_DIFF_85_IN5_DN")
			(clearance 0.10795)
			(padstack
				(mode front_inner_back)
				(layer "Inner"
					(shape circle)
					(size 0.8001 0.8001)
					(clearance 0.1524)
				)
				(layer "B.Cu"
					(shape circle)
					(size 1.0033 1.0033)
					(thermal_gap 0.10795)
					(clearance 0.10795)
				)
			)
		)
		(pad "2" thru_hole circle
			(at -2.54 0 90)
			(size 1.9939 1.9939)
			(drill 0.249936)
			(layers "*.Cu" "*.Mask")
			(remove_unused_layers no)
			(net "T1_GND")
			(clearance 0.10795)
			(padstack
				(mode front_inner_back)
				(layer "Inner"
					(shape circle)
					(size 0.8001 0.8001)
					(clearance 0.1524)
				)
				(layer "B.Cu"
					(shape circle)
					(size 1.9939 1.9939)
					(thermal_gap 0.10795)
					(clearance 0.10795)
				)
			)
		)
		(pad "3" thru_hole circle
			(at -2.54 2.54 90)
			(size 1.9939 1.9939)
			(drill 0.249936)
			(layers "*.Cu" "*.Mask")
			(remove_unused_layers no)
			(net "T1_GND")
			(clearance 0.10795)
			(padstack
				(mode front_inner_back)
				(layer "Inner"
					(shape circle)
					(size 0.8001 0.8001)
					(clearance 0.1524)
				)
				(layer "B.Cu"
					(shape circle)
					(size 1.9939 1.9939)
					(thermal_gap 0.10795)
					(clearance 0.10795)
				)
			)
		)
		(pad "4" thru_hole circle
			(at 0 2.54 90)
			(size 1.0033 1.0033)
			(drill 0.249936)
			(layers "*.Cu" "*.Mask")
			(remove_unused_layers no)
			(net "TDR_DIFF_85_IN5_DP")
			(clearance 0.10795)
			(padstack
				(mode front_inner_back)
				(layer "Inner"
					(shape circle)
					(size 0.8001 0.8001)
					(clearance 0.1524)
				)
				(layer "B.Cu"
					(shape circle)
					(size 1.0033 1.0033)
					(thermal_gap 0.10795)
					(clearance 0.10795)
				)
			)
		)
	)
	(footprint ""
		(layer "B.Cu")
		(at 426.757338 -332.627732 90)
		(property "Reference" "PR414"
			(at 0 0 90)
			(layer "B.SilkS")
			(hide yes)
			(effects
				(font
					(size 1.27 1.27)
				)
				(justify mirror)
			)
		)
		(property "Value" ""
			(at 0 0 90)
			(layer "B.Fab")
			(effects
				(font
					(size 1.27 1.27)
				)
				(justify mirror)
			)
		)
		(duplicate_pad_numbers_are_jumpers no)
		(fp_line
			(start 0.7874 -0.4064)
			(end -0.7874 -0.4064)
			(stroke
				(width 0.1524)
				(type default)
			)
			(layer "B.SilkS")
		)
		(fp_line
			(start -0.7874 -0.4064)
			(end -0.7874 0.4064)
			(stroke
				(width 0.1524)
				(type default)
			)
			(layer "B.SilkS")
		)
		(fp_line
			(start 0.7874 0.4064)
			(end 0.7874 -0.4064)
			(stroke
				(width 0.1524)
				(type default)
			)
			(layer "B.SilkS")
		)
		(fp_line
			(start -0.7874 0.4064)
			(end 0.7874 0.4064)
			(stroke
				(width 0.1524)
				(type default)
			)
			(layer "B.SilkS")
		)
		(fp_line
			(start 0.67945 -0.305054)
			(end 0.12065 -0.305054)
			(stroke
				(width 0.1)
				(type default)
			)
			(layer "B.Fab")
		)
		(fp_line
			(start 0.12065 -0.305054)
			(end 0.12065 -0.2794)
			(stroke
				(width 0.1)
				(type default)
			)
			(layer "B.Fab")
		)
		(fp_line
			(start -0.12065 -0.3048)
			(end -0.67945 -0.3048)
			(stroke
				(width 0.1)
				(type default)
			)
			(layer "B.Fab")
		)
		(fp_line
			(start -0.67945 -0.3048)
			(end -0.67945 0.3048)
			(stroke
				(width 0.1)
				(type default)
			)
			(layer "B.Fab")
		)
		(fp_line
			(start 0.12065 -0.2794)
			(end -0.12065 -0.2794)
			(stroke
				(width 0.1)
				(type default)
			)
			(layer "B.Fab")
		)
		(fp_line
			(start -0.12065 -0.2794)
			(end -0.12065 -0.3048)
			(stroke
				(width 0.1)
				(type default)
			)
			(layer "B.Fab")
		)
		(fp_line
			(start 0.12065 0.2794)
			(end 0.12065 0.3048)
			(stroke
				(width 0.1)
				(type default)
			)
			(layer "B.Fab")
		)
		(fp_line
			(start -0.120396 0.2794)
			(end 0.12065 0.2794)
			(stroke
				(width 0.1)
				(type default)
			)
			(layer "B.Fab")
		)
		(fp_line
			(start 0.67945 0.3048)
			(end 0.67945 -0.305054)
			(stroke
				(width 0.1)
				(type default)
			)
			(layer "B.Fab")
		)
		(fp_line
			(start 0.12065 0.3048)
			(end 0.67945 0.3048)
			(stroke
				(width 0.1)
				(type default)
			)
			(layer "B.Fab")
		)
		(fp_line
			(start -0.120396 0.3048)
			(end -0.120396 0.2794)
			(stroke
				(width 0.1)
				(type default)
			)
			(layer "B.Fab")
		)
		(fp_line
			(start -0.67945 0.3048)
			(end -0.120396 0.3048)
			(stroke
				(width 0.1)
				(type default)
			)
			(layer "B.Fab")
		)
		(pad "1" smd circle
			(at 0.40005 0 270)
			(size 0 0)
			(layers "B.Cu" "B.Mask" "B.Paste")
			(net "PVDD11_S3_P0")
		)
		(pad "2" smd circle
			(at -0.40005 0 270)
			(size 0 0)
			(layers "B.Cu" "B.Mask" "B.Paste")
			(net "GND")
		)
	)
	(footprint ""
		(layer "B.Cu")
		(at 79.886302 -335.060798 90)
		(property "Reference" "PC382_2"
			(at 0 0 90)
			(layer "B.SilkS")
			(hide yes)
			(effects
				(font
					(size 1.27 1.27)
				)
				(justify mirror)
			)
		)
		(property "Value" ""
			(at 0 0 90)
			(layer "B.Fab")
			(effects
				(font
					(size 1.27 1.27)
				)
				(justify mirror)
			)
		)
		(duplicate_pad_numbers_are_jumpers no)
		(fp_line
			(start 1.524 -0.762)
			(end -1.524 -0.762)
			(stroke
				(width 0.1524)
				(type default)
			)
			(layer "B.SilkS")
		)
		(fp_line
			(start -1.524 -0.762)
			(end -1.524 0.762)
			(stroke
				(width 0.1524)
				(type default)
			)
			(layer "B.SilkS")
		)
		(fp_line
			(start 1.524 0.762)
			(end 1.524 -0.762)
			(stroke
				(width 0.1524)
				(type default)
			)
			(layer "B.SilkS")
		)
		(fp_line
			(start -1.524 0.762)
			(end 1.524 0.762)
			(stroke
				(width 0.1524)
				(type default)
			)
			(layer "B.SilkS")
		)
		(fp_line
			(start 1.1049 -0.724916)
			(end 1.1049 0.724916)
			(stroke
				(width 0.1)
				(type default)
			)
			(layer "B.Fab")
		)
		(fp_line
			(start -1.1049 -0.724916)
			(end 1.1049 -0.724916)
			(stroke
				(width 0.1)
				(type default)
			)
			(layer "B.Fab")
		)
		(fp_line
			(start 1.1049 0.724916)
			(end -1.1049 0.724916)
			(stroke
				(width 0.1)
				(type default)
			)
			(layer "B.Fab")
		)
		(fp_line
			(start -1.1049 0.724916)
			(end -1.1049 -0.724916)
			(stroke
				(width 0.1)
				(type default)
			)
			(layer "B.Fab")
		)
		(pad "1" smd rect
			(at 0.889 0 90)
			(size 1.016 1.27)
			(layers "B.Cu" "B.Mask" "B.Paste")
			(net "SW_P12V_AUX_PVDDCR_CPU1_P1_FLT")
		)
		(pad "2" smd rect
			(at -0.889 0 90)
			(size 1.016 1.27)
			(layers "B.Cu" "B.Mask" "B.Paste")
			(net "GND")
		)
	)
	(footprint ""
		(layer "B.Cu")
		(at 339.148928 -312.053986)
		(property "Reference" "PR60"
			(at 0 0 0)
			(layer "B.SilkS")
			(hide yes)
			(effects
				(font
					(size 1.27 1.27)
				)
				(justify mirror)
			)
		)
		(property "Value" ""
			(at 0 0 0)
			(layer "B.Fab")
			(effects
				(font
					(size 1.27 1.27)
				)
				(justify mirror)
			)
		)
		(duplicate_pad_numbers_are_jumpers no)
		(fp_line
			(start -0.7874 -0.4064)
			(end -0.7874 0.4064)
			(stroke
				(width 0.1524)
				(type default)
			)
			(layer "B.SilkS")
		)
		(fp_line
			(start -0.7874 0.4064)
			(end 0.7874 0.4064)
			(stroke
				(width 0.1524)
				(type default)
			)
			(layer "B.SilkS")
		)
		(fp_line
			(start 0.7874 -0.4064)
			(end -0.7874 -0.4064)
			(stroke
				(width 0.1524)
				(type default)
			)
			(layer "B.SilkS")
		)
		(fp_line
			(start 0.7874 0.4064)
			(end 0.7874 -0.4064)
			(stroke
				(width 0.1524)
				(type default)
			)
			(layer "B.SilkS")
		)
		(fp_line
			(start -0.67945 -0.3048)
			(end -0.67945 0.3048)
			(stroke
				(width 0.1)
				(type default)
			)
			(layer "B.Fab")
		)
		(fp_line
			(start -0.67945 0.3048)
			(end -0.120396 0.3048)
			(stroke
				(width 0.1)
				(type default)
			)
			(layer "B.Fab")
		)
		(fp_line
			(start -0.12065 -0.3048)
			(end -0.67945 -0.3048)
			(stroke
				(width 0.1)
				(type default)
			)
			(layer "B.Fab")
		)
		(fp_line
			(start -0.12065 -0.2794)
			(end -0.12065 -0.3048)
			(stroke
				(width 0.1)
				(type default)
			)
			(layer "B.Fab")
		)
		(fp_line
			(start -0.120396 0.2794)
			(end 0.12065 0.2794)
			(stroke
				(width 0.1)
				(type default)
			)
			(layer "B.Fab")
		)
		(fp_line
			(start -0.120396 0.3048)
			(end -0.120396 0.2794)
			(stroke
				(width 0.1)
				(type default)
			)
			(layer "B.Fab")
		)
		(fp_line
			(start 0.12065 -0.305054)
			(end 0.12065 -0.2794)
			(stroke
				(width 0.1)
				(type default)
			)
			(layer "B.Fab")
		)
		(fp_line
			(start 0.12065 -0.2794)
			(end -0.12065 -0.2794)
			(stroke
				(width 0.1)
				(type default)
			)
			(layer "B.Fab")
		)
		(fp_line
			(start 0.12065 0.2794)
			(end 0.12065 0.3048)
			(stroke
				(width 0.1)
				(type default)
			)
			(layer "B.Fab")
		)
		(fp_line
			(start 0.12065 0.3048)
			(end 0.67945 0.3048)
			(stroke
				(width 0.1)
				(type default)
			)
			(layer "B.Fab")
		)
		(fp_line
			(start 0.67945 -0.305054)
			(end 0.12065 -0.305054)
			(stroke
				(width 0.1)
				(type default)
			)
			(layer "B.Fab")
		)
		(fp_line
			(start 0.67945 0.3048)
			(end 0.67945 -0.305054)
			(stroke
				(width 0.1)
				(type default)
			)
			(layer "B.Fab")
		)
		(pad "1" smd circle
			(at 0.40005 0 180)
			(size 0 0)
			(layers "B.Cu" "B.Mask" "B.Paste")
			(net "SVID_PVDDCR_CPU1_P0_SVD_R")
		)
		(pad "2" smd circle
			(at -0.40005 0 180)
			(size 0 0)
			(layers "B.Cu" "B.Mask" "B.Paste")
			(net "SVID_PVDDCR_CPU1_P0_SVD")
		)
	)
)
